(kicad_pcb
	(version 20241229)
	(generator "pcbnew")
	(generator_version "9.0")
	(general
		(thickness 1.61)
		(legacy_teardrops no)
	)
	(paper "A3")
	(title_block
		(title "RDIMM DDR5 Tester")
		(date "2026-05-21")
		(rev "2.2.0")
		(company "Antmicro")
		(comment 9 "footprint 119 of 796 (U34), pads 673-676 of 676")
	)
	(layers
		(0 "F.Cu" signal)
		(4 "In1.Cu" power)
		(6 "In2.Cu" mixed)
		(8 "In3.Cu" power)
		(10 "In4.Cu" mixed)
		(12 "In5.Cu" power)
		(14 "In6.Cu" mixed)
		(16 "In7.Cu" power)
		(18 "In8.Cu" power)
		(20 "In9.Cu" mixed)
		(22 "In10.Cu" power)
		(2 "B.Cu" signal)
		(9 "F.Adhes" user "F.Adhesive")
		(11 "B.Adhes" user "B.Adhesive")
		(13 "F.Paste" user)
		(15 "B.Paste" user)
		(5 "F.SilkS" user "F.Silkscreen")
		(7 "B.SilkS" user "B.Silkscreen")
		(1 "F.Mask" user)
		(3 "B.Mask" user)
		(17 "Dwgs.User" user "User.Drawings")
		(19 "Cmts.User" user "User.Comments")
		(21 "Eco1.User" user "User.Eco1")
		(23 "Eco2.User" user "User.Eco2")
		(25 "Edge.Cuts" user)
		(27 "Margin" user)
		(31 "F.CrtYd" user "F.Courtyard")
		(29 "B.CrtYd" user "B.Courtyard")
		(35 "F.Fab" user)
		(33 "B.Fab" user)
	)
	(footprint "antmicro-footprints:BGA-676_27x27mm_Layout26x26_P1x1mm_FFVB676"
		(layer "F.Cu")
		(at 188.5 152.5 90)
		(property "Reference" "U34"
			(at -14.72 12.46 180)
			(layer "F.SilkS")
			(effects
				(font
					(size 0.7 0.7)
					(thickness 0.15)
				)
				(justify left bottom)
			)
		)
		(property "Value" "XCAU25P-2FFVB676I"
			(at 0 15.5 90)
			(layer "F.Fab")
			(effects
				(font
					(size 0.7 0.7)
					(thickness 0.15)
				)
				(justify left bottom)
			)
		)
		(property "Datasheet" "https://docs.xilinx.com/viewer/book-attachment/2PXOpPtpaABIt0fkzeBLnw/hvbsEUaOT0OxFhln7VEVyA"
			(at 0 0 90)
			(layer "F.Fab")
			(hide yes)
			(effects
				(font
					(size 1.27 1.27)
					(thickness 0.15)
				)
			)
		)
		(property "MPN" "XCAU25P-2FFVB676I"
			(at 0 0 90)
			(unlocked yes)
			(layer "F.Fab")
			(hide yes)
			(effects
				(font
					(size 1 1)
					(thickness 0.15)
				)
			)
		)
		(property "Manufacturer" "AMD-Xilinx"
			(at 0 0 90)
			(unlocked yes)
			(layer "F.Fab")
			(hide yes)
			(effects
				(font
					(size 1 1)
					(thickness 0.15)
				)
			)
		)
		(property "Author" "Antmicro"
			(at 0 0 90)
			(unlocked yes)
			(layer "F.Fab")
			(hide yes)
			(effects
				(font
					(size 1 1)
					(thickness 0.15)
				)
			)
		)
		(property "License" "Apache-2.0"
			(at 0 0 90)
			(unlocked yes)
			(layer "F.Fab")
			(hide yes)
			(effects
				(font
					(size 1 1)
					(thickness 0.15)
				)
			)
		)
		(sheetname "/FPGA Config/")
		(sheetfile "fpga-config.kicad_sch")
		(attr smd)
		(pad "Y23" smd circle
			(at 9.5 6.5 90)
			(size 0.5 0.5)
			(layers "F.Cu" "F.Mask" "F.Paste")
			(net 191 "/DDR5 RDIMM/A.CS1_c")
			(pinfunction "IO_L7N_T1L_N1_QBC_AD13N_A19_65")
			(pintype "bidirectional")
			(die_length 12.82)
			(solder_mask_margin 0.075)
		)
		(pad "Y24" smd circle
			(at 10.5 6.5 90)
			(size 0.5 0.5)
			(layers "F.Cu" "F.Mask" "F.Paste")
			(net 687 "VDDQ")
			(pinfunction "VCCO_65")
			(pintype "passive")
			(solder_mask_margin 0.075)
		)
		(pad "Y25" smd circle
			(at 11.5 6.5 90)
			(size 0.5 0.5)
			(layers "F.Cu" "F.Mask" "F.Paste")
			(net 76 "/DDR5 RDIMM/A.CA4")
			(pinfunction "IO_L8P_T1L_N2_AD5P_A16_65")
			(pintype "bidirectional")
			(die_length 12.979)
			(solder_mask_margin 0.075)
		)
		(pad "Y26" smd circle
			(at 12.5 6.5 90)
			(size 0.5 0.5)
			(layers "F.Cu" "F.Mask" "F.Paste")
			(net 194 "/DDR5 RDIMM/A.CA5")
			(pinfunction "IO_L8N_T1L_N3_AD5N_A17_65")
			(pintype "bidirectional")
			(die_length 13.135)
			(solder_mask_margin 0.075)
		)
	)
)
